# T6G (Grand Teton) — schematic netlist excerpt (pin names and nets, part order shuffled) for the footprints in the layout excerpt that follows; sources: Cadence DE-HDL packaged netlist, KiCad conversion of 04192023_DAF0TMB3IC0_F0TG_MB_C_brd_V02_OCP.brd

R952  Q_RES  0 5% EMPTY  pkg 0402LF  page 279 : A = P1V8_CPU0_RT0_1A_1D ; B = P1V8_CPU0_RT0_1A
C8066  Q_CAP  1000PF 50V 5% X7R  pkg 0402  page 200 : A = PVDDIO_P0_EN_R ; B = GND

(kicad_pcb
	(version 20260206)
	(generator "pcbnew")
	(generator_version "10.0")
	(general
		(thickness 1.6)
		(legacy_teardrops no)
	)
	(paper "A4")
	(title_block
		(title "04192023_DAF0TMB3IC0_F0TG_MB_C_brd_V02_OCP.brd")
		(comment 1 "Grand Teton / footprints 493-494 of 8354")
	)
	(layers
		(0 "F.Cu" signal "TOP")
		(4 "In1.Cu" signal "GND")
		(6 "In2.Cu" signal "IN1")
		(8 "In3.Cu" signal "GND1")
		(10 "In4.Cu" signal "IN2")
		(12 "In5.Cu" signal "GND2")
		(14 "In6.Cu" signal "IN3")
		(16 "In7.Cu" signal "GND3")
		(18 "In8.Cu" signal "VCC")
		(20 "In9.Cu" signal "VCC1")
		(22 "In10.Cu" signal "GND4")
		(24 "In11.Cu" signal "IN4")
		(26 "In12.Cu" signal "GND5")
		(28 "In13.Cu" signal "IN5")
		(30 "In14.Cu" signal "GND6")
		(32 "In15.Cu" signal "IN6")
		(34 "In16.Cu" signal "GND7")
		(2 "B.Cu" signal "BOTTOM")
		(9 "F.Adhes" user "F.Adhesive")
		(11 "B.Adhes" user "B.Adhesive")
		(13 "F.Paste" user "Package Geometry/Pastemask Top")
		(15 "B.Paste" user "Package Geometry/Pastemask Bottom")
		(5 "F.SilkS" user "Ref Des/Silkscreen Top")
		(7 "B.SilkS" user "Ref Des/Silkscreen Bottom")
		(1 "F.Mask" user "Board Geometry/Soldermask Top")
		(3 "B.Mask" user "Board Geometry/Soldermask Bottom")
		(17 "Dwgs.User" user "User.Drawings")
		(19 "Cmts.User" user "User.Comments")
		(21 "Eco1.User" user "User.Eco1")
		(23 "Eco2.User" user "User.Eco2")
		(25 "Edge.Cuts" user "Board Geometry/Outline")
		(27 "Margin" user)
		(31 "F.CrtYd" user "Package Geometry/Place Bound Top")
		(29 "B.CrtYd" user "Package Geometry/Place Bound Bottom")
		(35 "F.Fab" user "Ref Des/Assembly Top")
		(33 "B.Fab" user "Ref Des/Assembly Bottom")
	)
	(footprint ""
		(layer "F.Cu")
		(at 289.012884 -370.318792 -90)
		(property "Reference" "C8066"
			(at 0 0 270)
			(layer "F.SilkS")
			(hide yes)
			(effects
				(font
					(size 1.27 1.27)
				)
			)
		)
		(property "Value" ""
			(at 0 0 270)
			(layer "F.Fab")
			(effects
				(font
					(size 1.27 1.27)
				)
			)
		)
		(duplicate_pad_numbers_are_jumpers no)
		(fp_line
			(start -0.7874 0.4064)
			(end -0.7874 -0.4064)
			(stroke
				(width 0.1524)
				(type default)
			)
			(layer "F.SilkS")
		)
		(fp_line
			(start 0.7874 0.4064)
			(end -0.7874 0.4064)
			(stroke
				(width 0.1524)
				(type default)
			)
			(layer "F.SilkS")
		)
		(fp_line
			(start -0.7874 -0.4064)
			(end 0.7874 -0.4064)
			(stroke
				(width 0.1524)
				(type default)
			)
			(layer "F.SilkS")
		)
		(fp_line
			(start 0.7874 -0.4064)
			(end 0.7874 0.4064)
			(stroke
				(width 0.1524)
				(type default)
			)
			(layer "F.SilkS")
		)
		(fp_line
			(start -0.67945 0.3048)
			(end -0.67945 -0.305054)
			(stroke
				(width 0.1)
				(type default)
			)
			(layer "F.Fab")
		)
		(fp_line
			(start -0.12065 0.3048)
			(end -0.67945 0.3048)
			(stroke
				(width 0.1)
				(type default)
			)
			(layer "F.Fab")
		)
		(fp_line
			(start 0.120396 0.3048)
			(end 0.120396 0.2794)
			(stroke
				(width 0.1)
				(type default)
			)
			(layer "F.Fab")
		)
		(fp_line
			(start 0.67945 0.3048)
			(end 0.120396 0.3048)
			(stroke
				(width 0.1)
				(type default)
			)
			(layer "F.Fab")
		)
		(fp_line
			(start -0.12065 0.2794)
			(end -0.12065 0.3048)
			(stroke
				(width 0.1)
				(type default)
			)
			(layer "F.Fab")
		)
		(fp_line
			(start 0.120396 0.2794)
			(end -0.12065 0.2794)
			(stroke
				(width 0.1)
				(type default)
			)
			(layer "F.Fab")
		)
		(fp_line
			(start -0.12065 -0.2794)
			(end 0.12065 -0.2794)
			(stroke
				(width 0.1)
				(type default)
			)
			(layer "F.Fab")
		)
		(fp_line
			(start 0.12065 -0.2794)
			(end 0.12065 -0.3048)
			(stroke
				(width 0.1)
				(type default)
			)
			(layer "F.Fab")
		)
		(fp_line
			(start 0.12065 -0.3048)
			(end 0.67945 -0.3048)
			(stroke
				(width 0.1)
				(type default)
			)
			(layer "F.Fab")
		)
		(fp_line
			(start 0.67945 -0.3048)
			(end 0.67945 0.3048)
			(stroke
				(width 0.1)
				(type default)
			)
			(layer "F.Fab")
		)
		(fp_line
			(start -0.67945 -0.305054)
			(end -0.12065 -0.305054)
			(stroke
				(width 0.1)
				(type default)
			)
			(layer "F.Fab")
		)
		(fp_line
			(start -0.12065 -0.305054)
			(end -0.12065 -0.2794)
			(stroke
				(width 0.1)
				(type default)
			)
			(layer "F.Fab")
		)
		(pad "1" smd circle
			(at -0.40005 0 270)
			(size 0 0)
			(layers "F.Cu" "F.Mask" "F.Paste")
			(net "PVDDIO_P0_EN_R")
		)
		(pad "2" smd circle
			(at 0.40005 0 270)
			(size 0 0)
			(layers "F.Cu" "F.Mask" "F.Paste")
			(net "GND")
		)
	)
	(footprint ""
		(layer "F.Cu")
		(at 325.862188 -392.48588 180)
		(property "Reference" "R952"
			(at 0 0 180)
			(layer "F.SilkS")
			(hide yes)
			(effects
				(font
					(size 1.27 1.27)
				)
			)
		)
		(property "Value" ""
			(at 0 0 180)
			(layer "F.Fab")
			(effects
				(font
					(size 1.27 1.27)
				)
			)
		)
		(duplicate_pad_numbers_are_jumpers no)
		(fp_line
			(start 0.7874 0.4064)
			(end -0.7874 0.4064)
			(stroke
				(width 0.1524)
				(type default)
			)
			(layer "F.SilkS")
		)
		(fp_line
			(start 0.7874 -0.4064)
			(end 0.7874 0.4064)
			(stroke
				(width 0.1524)
				(type default)
			)
			(layer "F.SilkS")
		)
		(fp_line
			(start -0.7874 0.4064)
			(end -0.7874 -0.4064)
			(stroke
				(width 0.1524)
				(type default)
			)
			(layer "F.SilkS")
		)
		(fp_line
			(start -0.7874 -0.4064)
			(end 0.7874 -0.4064)
			(stroke
				(width 0.1524)
				(type default)
			)
			(layer "F.SilkS")
		)
		(fp_line
			(start 0.67945 0.3048)
			(end 0.120396 0.3048)
			(stroke
				(width 0.1)
				(type default)
			)
			(layer "F.Fab")
		)
		(fp_line
			(start 0.67945 -0.3048)
			(end 0.67945 0.3048)
			(stroke
				(width 0.1)
				(type default)
			)
			(layer "F.Fab")
		)
		(fp_line
			(start 0.12065 -0.2794)
			(end 0.12065 -0.3048)
			(stroke
				(width 0.1)
				(type default)
			)
			(layer "F.Fab")
		)
		(fp_line
			(start 0.12065 -0.3048)
			(end 0.67945 -0.3048)
			(stroke
				(width 0.1)
				(type default)
			)
			(layer "F.Fab")
		)
		(fp_line
			(start 0.120396 0.3048)
			(end 0.120396 0.2794)
			(stroke
				(width 0.1)
				(type default)
			)
			(layer "F.Fab")
		)
		(fp_line
			(start 0.120396 0.2794)
			(end -0.12065 0.2794)
			(stroke
				(width 0.1)
				(type default)
			)
			(layer "F.Fab")
		)
		(fp_line
			(start -0.12065 0.3048)
			(end -0.67945 0.3048)
			(stroke
				(width 0.1)
				(type default)
			)
			(layer "F.Fab")
		)
		(fp_line
			(start -0.12065 0.2794)
			(end -0.12065 0.3048)
			(stroke
				(width 0.1)
				(type default)
			)
			(layer "F.Fab")
		)
		(fp_line
			(start -0.12065 -0.2794)
			(end 0.12065 -0.2794)
			(stroke
				(width 0.1)
				(type default)
			)
			(layer "F.Fab")
		)
		(fp_line
			(start -0.12065 -0.305054)
			(end -0.12065 -0.2794)
			(stroke
				(width 0.1)
				(type default)
			)
			(layer "F.Fab")
		)
		(fp_line
			(start -0.67945 0.3048)
			(end -0.67945 -0.305054)
			(stroke
				(width 0.1)
				(type default)
			)
			(layer "F.Fab")
		)
		(fp_line
			(start -0.67945 -0.305054)
			(end -0.12065 -0.305054)
			(stroke
				(width 0.1)
				(type default)
			)
			(layer "F.Fab")
		)
		(pad "1" smd rect
			(at -0.40005 0)
			(size 0.4572 0.508)
			(layers "F.Cu" "F.Mask" "F.Paste")
			(net "P1V8_CPU0_RT0_1A_1D")
		)
		(pad "2" smd rect
			(at 0.40005 0)
			(size 0.4572 0.508)
			(layers "F.Cu" "F.Mask" "F.Paste")
			(net "P1V8_CPU0_RT0_1A")
		)
	)
)
